(kicad_pcb
	(version 20260206)
	(generator "pcbnew")
	(generator_version "10.0")
	(general
		(thickness 1.6)
		(legacy_teardrops no)
	)
	(paper "A4")
	(title_block
		(title "Bryce Canyon_R.DPB_16317-1_OCP.brd")
		(comment 1 "Bryce Canyon / footprints 181-187 of 2099")
	)
	(layers
		(0 "F.Cu" signal "TOP")
		(4 "In1.Cu" signal "L2GND")
		(6 "In2.Cu" signal "L3")
		(8 "In3.Cu" signal "L4VCC")
		(10 "In4.Cu" signal "L5VCC")
		(12 "In5.Cu" signal "L6")
		(14 "In6.Cu" signal "L7GND")
		(2 "B.Cu" signal "BOTTOM")
		(9 "F.Adhes" user "F.Adhesive")
		(11 "B.Adhes" user "B.Adhesive")
		(13 "F.Paste" user "Package Geometry/Pastemask Top")
		(15 "B.Paste" user "Package Geometry/Pastemask Bottom")
		(5 "F.SilkS" user "Ref Des/Silkscreen Top")
		(7 "B.SilkS" user "Ref Des/Silkscreen Bottom")
		(1 "F.Mask" user "Board Geometry/Soldermask Top")
		(3 "B.Mask" user "Board Geometry/Soldermask Bottom")
		(17 "Dwgs.User" user "User.Drawings")
		(19 "Cmts.User" user "User.Comments")
		(21 "Eco1.User" user "User.Eco1")
		(23 "Eco2.User" user "User.Eco2")
		(25 "Edge.Cuts" user "Board Geometry/Outline")
		(27 "Margin" user)
		(31 "F.CrtYd" user "Package Geometry/Place Bound Top")
		(29 "B.CrtYd" user "Package Geometry/Place Bound Bottom")
		(35 "F.Fab" user "Ref Des/Assembly Top")
		(33 "B.Fab" user "Ref Des/Assembly Bottom")
	)
	(footprint ""
		(layer "F.Cu")
		(at 64.013334 -244.660674 90)
		(property "Reference" "C42"
			(at 0 0 90)
			(layer "F.SilkS")
			(hide yes)
			(effects
				(font
					(size 1.27 1.27)
				)
			)
		)
		(property "Value" "SCD01U16V1KX-GP"
			(at -2.8321 -1.7399 90)
			(unlocked yes)
			(layer "F.Fab")
			(hide yes)
			(effects
				(font
					(size 1.016 1.016)
					(thickness 0.1524)
				)
			)
		)
		(property "Device Type" "C0201H13"
			(at -2.8321 -3.2639 90)
			(unlocked yes)
			(layer "F.Fab")
			(hide yes)
			(effects
				(font
					(size 1.016 1.016)
					(thickness 0.1524)
				)
			)
		)
		(duplicate_pad_numbers_are_jumpers no)
		(fp_rect
			(start -0.2794 0.6477)
			(end 0.2794 -0.6477)
			(stroke
				(width 0)
				(type default)
			)
			(fill no)
			(layer "F.CrtYd")
		)
		(fp_rect
			(start -0.2794 0.6477)
			(end 0.2794 -0.6477)
			(stroke
				(width 0)
				(type default)
			)
			(fill no)
			(layer "F.Fab")
		)
		(pad "1" smd custom
			(at 0 -0.2794 90)
			(size 0.0762 0.0762)
			(layers "F.Cu" "F.Mask" "F.Paste")
			(net "SAS_HDD_RX_P1")
			(options
				(clearance outline)
				(anchor circle)
			)
			(primitives
				(gr_poly
					(pts
						(arc
							(start 0.1524 -0.127)
							(mid 0.137521 -0.162921)
							(end 0.1016 -0.1778)
						)
						(arc
							(start -0.1016 -0.1778)
							(mid -0.137521 -0.162921)
							(end -0.1524 -0.127)
						)
						(arc
							(start -0.1524 0.127)
							(mid -0.137521 0.162921)
							(end -0.1016 0.1778)
						)
						(arc
							(start 0.1016 0.1778)
							(mid 0.137521 0.162921)
							(end 0.1524 0.127)
						)
					)
					(width 0)
					(fill yes)
				)
			)
		)
		(pad "2" smd custom
			(at 0 0.2794 90)
			(size 0.0762 0.0762)
			(layers "F.Cu" "F.Mask" "F.Paste")
			(net "PHY_SCC_B_TO_DRV_B_1_DP")
			(options
				(clearance outline)
				(anchor circle)
			)
			(primitives
				(gr_poly
					(pts
						(arc
							(start 0.1524 -0.127)
							(mid 0.137521 -0.162921)
							(end 0.1016 -0.1778)
						)
						(arc
							(start -0.1016 -0.1778)
							(mid -0.137521 -0.162921)
							(end -0.1524 -0.127)
						)
						(arc
							(start -0.1524 0.127)
							(mid -0.137521 0.162921)
							(end -0.1016 0.1778)
						)
						(arc
							(start 0.1016 0.1778)
							(mid 0.137521 0.162921)
							(end 0.1524 0.127)
						)
					)
					(width 0)
					(fill yes)
				)
			)
		)
	)
	(footprint ""
		(layer "F.Cu")
		(at 249.032268 -222.9612 180)
		(property "Reference" "R112"
			(at 0 0 180)
			(layer "F.SilkS")
			(hide yes)
			(effects
				(font
					(size 1.27 1.27)
				)
			)
		)
		(property "Value" "4K7R2F-GP"
			(at 0.064008 -3.993896 180)
			(unlocked yes)
			(layer "F.Fab")
			(hide yes)
			(effects
				(font
					(size 1.016 1.016)
					(thickness 0.1524)
				)
			)
		)
		(property "Device Type" "R402H16"
			(at 0.064008 -5.517896 180)
			(unlocked yes)
			(layer "F.Fab")
			(hide yes)
			(effects
				(font
					(size 1.016 1.016)
					(thickness 0.1524)
				)
			)
		)
		(duplicate_pad_numbers_are_jumpers no)
		(fp_line
			(start 0.508 -0.9398)
			(end -0.508 -0.9398)
			(stroke
				(width 0.1524)
				(type default)
			)
			(layer "F.SilkS")
		)
		(fp_line
			(start -0.508 -0.9398)
			(end -0.508 0.9398)
			(stroke
				(width 0.1524)
				(type default)
			)
			(layer "F.SilkS")
		)
		(fp_rect
			(start -0.508 0.9398)
			(end 0.508 -0.9398)
			(stroke
				(width 0)
				(type default)
			)
			(fill no)
			(layer "F.CrtYd")
		)
		(fp_rect
			(start -0.508 0.9398)
			(end 0.508 -0.9398)
			(stroke
				(width 0)
				(type default)
			)
			(fill no)
			(layer "F.Fab")
		)
		(pad "1" smd custom
			(at 0 -0.4445 180)
			(size 0.1397 0.1397)
			(layers "F.Cu" "F.Mask" "F.Paste")
			(net "EEPROM_A1")
			(options
				(clearance outline)
				(anchor circle)
			)
			(primitives
				(gr_poly
					(pts
						(arc
							(start -0.1778 -0.2794)
							(mid -0.249642 -0.249642)
							(end -0.2794 -0.1778)
						)
						(arc
							(start -0.2794 0.1778)
							(mid -0.249642 0.249642)
							(end -0.1778 0.2794)
						)
						(arc
							(start 0.1778 0.2794)
							(mid 0.249642 0.249642)
							(end 0.2794 0.1778)
						)
						(arc
							(start 0.2794 -0.1778)
							(mid 0.249642 -0.249642)
							(end 0.1778 -0.2794)
						)
					)
					(width 0)
					(fill yes)
				)
			)
		)
		(pad "2" smd custom
			(at 0 0.4445 180)
			(size 0.1397 0.1397)
			(layers "F.Cu" "F.Mask" "F.Paste")
			(net "GND")
			(options
				(clearance outline)
				(anchor circle)
			)
			(primitives
				(gr_poly
					(pts
						(arc
							(start -0.1778 -0.2794)
							(mid -0.249642 -0.249642)
							(end -0.2794 -0.1778)
						)
						(arc
							(start -0.2794 0.1778)
							(mid -0.249642 0.249642)
							(end -0.1778 0.2794)
						)
						(arc
							(start 0.1778 0.2794)
							(mid 0.249642 0.249642)
							(end 0.2794 0.1778)
						)
						(arc
							(start 0.2794 -0.1778)
							(mid 0.249642 -0.249642)
							(end 0.1778 -0.2794)
						)
					)
					(width 0)
					(fill yes)
				)
			)
		)
	)
	(footprint ""
		(layer "F.Cu")
		(at 458.216 -246.253 -90)
		(property "Reference" "Q39"
			(at 0 0 270)
			(layer "F.SilkS")
			(hide yes)
			(effects
				(font
					(size 1.27 1.27)
				)
			)
		)
		(property "Value" "2N7002KDW-GP"
			(at -2.3622 -8.2042 270)
			(unlocked yes)
			(layer "F.Fab")
			(hide yes)
			(effects
				(font
					(size 1.016 1.016)
					(thickness 0.1524)
				)
			)
		)
		(property "Device Type" "SOT-363H44"
			(at -2.3622 -10.1092 270)
			(unlocked yes)
			(layer "F.Fab")
			(hide yes)
			(effects
				(font
					(size 1.016 1.016)
					(thickness 0.1524)
				)
			)
		)
		(duplicate_pad_numbers_are_jumpers no)
		(fp_line
			(start -1.4478 1.7018)
			(end 1.4478 1.7018)
			(stroke
				(width 0.1524)
				(type default)
			)
			(layer "F.SilkS")
		)
		(fp_line
			(start 1.4478 1.7018)
			(end 1.4478 -1.7018)
			(stroke
				(width 0.1524)
				(type default)
			)
			(layer "F.SilkS")
		)
		(fp_line
			(start -1.27 1.524)
			(end -1.27 0.6604)
			(stroke
				(width 0.4826)
				(type default)
			)
			(layer "F.SilkS")
		)
		(fp_line
			(start -1.4478 -1.7018)
			(end -1.4478 1.7018)
			(stroke
				(width 0.1524)
				(type default)
			)
			(layer "F.SilkS")
		)
		(fp_line
			(start 1.4478 -1.7018)
			(end -1.4478 -1.7018)
			(stroke
				(width 0.1524)
				(type default)
			)
			(layer "F.SilkS")
		)
		(fp_poly
			(pts
				(xy -1.524 -1.778) (xy 1.524 -1.778) (xy 1.524 1.778) (xy -1.524 1.778)
			)
			(stroke
				(width 0)
				(type default)
			)
			(fill no)
			(layer "F.CrtYd")
		)
		(fp_poly
			(pts
				(xy -1.524 -1.778) (xy 1.524 -1.778) (xy 1.524 1.778) (xy -1.524 1.778)
			)
			(stroke
				(width 0)
				(type default)
			)
			(fill no)
			(layer "F.Fab")
		)
		(pad "1" smd rect
			(at -0.65024 0.9398 270)
			(size 0.4064 1.016)
			(layers "F.Cu" "F.Mask" "F.Paste")
			(net "GND")
		)
		(pad "2" smd rect
			(at 0 0.9398 270)
			(size 0.4064 1.016)
			(layers "F.Cu" "F.Mask" "F.Paste")
			(net "SW_PWR_R_HDD10")
		)
		(pad "3" smd rect
			(at 0.65024 0.9398 270)
			(size 0.4064 1.016)
			(layers "F.Cu" "F.Mask" "F.Paste")
			(net "SW_HDD_P10")
		)
		(pad "4" smd rect
			(at 0.65024 -0.9398 270)
			(size 0.4064 1.016)
			(layers "F.Cu" "F.Mask" "F.Paste")
			(net "GND")
		)
		(pad "5" smd rect
			(at 0 -0.9398 270)
			(size 0.4064 1.016)
			(layers "F.Cu" "F.Mask" "F.Paste")
			(net "SW_HDD_G10")
		)
		(pad "6" smd rect
			(at -0.65024 -0.9398 270)
			(size 0.4064 1.016)
			(layers "F.Cu" "F.Mask" "F.Paste")
			(net "SW_HDD_R10")
		)
	)
	(footprint ""
		(layer "F.Cu")
		(at 95.563436 -14.660626 90)
		(property "Reference" "C367"
			(at 0 0 90)
			(layer "F.SilkS")
			(hide yes)
			(effects
				(font
					(size 1.27 1.27)
				)
			)
		)
		(property "Value" "SCD01U16V1KX-GP"
			(at -2.8321 -1.7399 90)
			(unlocked yes)
			(layer "F.Fab")
			(hide yes)
			(effects
				(font
					(size 1.016 1.016)
					(thickness 0.1524)
				)
			)
		)
		(property "Device Type" "C0201H13"
			(at -2.8321 -3.2639 90)
			(unlocked yes)
			(layer "F.Fab")
			(hide yes)
			(effects
				(font
					(size 1.016 1.016)
					(thickness 0.1524)
				)
			)
		)
		(duplicate_pad_numbers_are_jumpers no)
		(fp_rect
			(start -0.2794 0.6477)
			(end 0.2794 -0.6477)
			(stroke
				(width 0)
				(type default)
			)
			(fill no)
			(layer "F.CrtYd")
		)
		(fp_rect
			(start -0.2794 0.6477)
			(end 0.2794 -0.6477)
			(stroke
				(width 0)
				(type default)
			)
			(fill no)
			(layer "F.Fab")
		)
		(pad "1" smd custom
			(at 0 -0.2794 90)
			(size 0.0762 0.0762)
			(layers "F.Cu" "F.Mask" "F.Paste")
			(net "SAS_HDD_RX_P26")
			(options
				(clearance outline)
				(anchor circle)
			)
			(primitives
				(gr_poly
					(pts
						(arc
							(start 0.1524 -0.127)
							(mid 0.137521 -0.162921)
							(end 0.1016 -0.1778)
						)
						(arc
							(start -0.1016 -0.1778)
							(mid -0.137521 -0.162921)
							(end -0.1524 -0.127)
						)
						(arc
							(start -0.1524 0.127)
							(mid -0.137521 0.162921)
							(end -0.1016 0.1778)
						)
						(arc
							(start 0.1016 0.1778)
							(mid 0.137521 0.162921)
							(end 0.1524 0.127)
						)
					)
					(width 0)
					(fill yes)
				)
			)
		)
		(pad "2" smd custom
			(at 0 0.2794 90)
			(size 0.0762 0.0762)
			(layers "F.Cu" "F.Mask" "F.Paste")
			(net "PHY_SCC_B_TO_DRV_B_26_DP")
			(options
				(clearance outline)
				(anchor circle)
			)
			(primitives
				(gr_poly
					(pts
						(arc
							(start 0.1524 -0.127)
							(mid 0.137521 -0.162921)
							(end 0.1016 -0.1778)
						)
						(arc
							(start -0.1016 -0.1778)
							(mid -0.137521 -0.162921)
							(end -0.1524 -0.127)
						)
						(arc
							(start -0.1524 0.127)
							(mid -0.137521 0.162921)
							(end -0.1016 0.1778)
						)
						(arc
							(start 0.1016 0.1778)
							(mid 0.137521 0.162921)
							(end 0.1524 0.127)
						)
					)
					(width 0)
					(fill yes)
				)
			)
		)
	)
	(footprint ""
		(layer "F.Cu")
		(at 459.359 -128.651 180)
		(property "Reference" "R584"
			(at 0 0 180)
			(layer "F.SilkS")
			(hide yes)
			(effects
				(font
					(size 1.27 1.27)
				)
			)
		)
		(property "Value" "1KR2F-3-GP"
			(at 0.064008 -3.993896 180)
			(unlocked yes)
			(layer "F.Fab")
			(hide yes)
			(effects
				(font
					(size 1.016 1.016)
					(thickness 0.1524)
				)
			)
		)
		(property "Device Type" "R402H16"
			(at 0.064008 -5.517896 180)
			(unlocked yes)
			(layer "F.Fab")
			(hide yes)
			(effects
				(font
					(size 1.016 1.016)
					(thickness 0.1524)
				)
			)
		)
		(duplicate_pad_numbers_are_jumpers no)
		(fp_line
			(start 0.508 -0.9398)
			(end -0.508 -0.9398)
			(stroke
				(width 0.1524)
				(type default)
			)
			(layer "F.SilkS")
		)
		(fp_line
			(start -0.508 -0.9398)
			(end -0.508 0.9398)
			(stroke
				(width 0.1524)
				(type default)
			)
			(layer "F.SilkS")
		)
		(fp_rect
			(start -0.508 0.9398)
			(end 0.508 -0.9398)
			(stroke
				(width 0)
				(type default)
			)
			(fill no)
			(layer "F.CrtYd")
		)
		(fp_rect
			(start -0.508 0.9398)
			(end 0.508 -0.9398)
			(stroke
				(width 0)
				(type default)
			)
			(fill no)
			(layer "F.Fab")
		)
		(pad "1" smd custom
			(at 0 -0.4445 180)
			(size 0.1397 0.1397)
			(layers "F.Cu" "F.Mask" "F.Paste")
			(net "P3V3_STBY_B")
			(options
				(clearance outline)
				(anchor circle)
			)
			(primitives
				(gr_poly
					(pts
						(arc
							(start -0.1778 -0.2794)
							(mid -0.249642 -0.249642)
							(end -0.2794 -0.1778)
						)
						(arc
							(start -0.2794 0.1778)
							(mid -0.249642 0.249642)
							(end -0.1778 0.2794)
						)
						(arc
							(start 0.1778 0.2794)
							(mid 0.249642 0.249642)
							(end 0.2794 0.1778)
						)
						(arc
							(start 0.2794 -0.1778)
							(mid 0.249642 -0.249642)
							(end 0.1778 -0.2794)
						)
					)
					(width 0)
					(fill yes)
				)
			)
		)
		(pad "2" smd custom
			(at 0 0.4445 180)
			(size 0.1397 0.1397)
			(layers "F.Cu" "F.Mask" "F.Paste")
			(net "SW_PWR_R_HDD22")
			(options
				(clearance outline)
				(anchor circle)
			)
			(primitives
				(gr_poly
					(pts
						(arc
							(start -0.1778 -0.2794)
							(mid -0.249642 -0.249642)
							(end -0.2794 -0.1778)
						)
						(arc
							(start -0.2794 0.1778)
							(mid -0.249642 0.249642)
							(end -0.1778 0.2794)
						)
						(arc
							(start 0.1778 0.2794)
							(mid 0.249642 0.249642)
							(end 0.2794 0.1778)
						)
						(arc
							(start 0.2794 -0.1778)
							(mid 0.249642 -0.249642)
							(end 0.1778 -0.2794)
						)
					)
					(width 0)
					(fill yes)
				)
			)
		)
	)
	(footprint ""
		(layer "F.Cu")
		(at 282.448 -343.916 -90)
		(property "Reference" "C34"
			(at 0 0 270)
			(layer "F.SilkS")
			(hide yes)
			(effects
				(font
					(size 1.27 1.27)
				)
			)
		)
		(property "Value" "SC1U16V3KX-5GP"
			(at 0 -2.8194 270)
			(unlocked yes)
			(layer "F.Fab")
			(hide yes)
			(effects
				(font
					(size 1.016 1.016)
					(thickness 0.1524)
				)
			)
		)
		(property "Device Type" "C603H36"
			(at 0 -4.3434 270)
			(unlocked yes)
			(layer "F.Fab")
			(hide yes)
			(effects
				(font
					(size 1.016 1.016)
					(thickness 0.1524)
				)
			)
		)
		(duplicate_pad_numbers_are_jumpers no)
		(fp_line
			(start 0.508 0)
			(end -0.508 0)
			(stroke
				(width 0.2032)
				(type default)
			)
			(layer "F.SilkS")
		)
		(fp_rect
			(start -0.5842 1.3335)
			(end 0.5842 -1.3335)
			(stroke
				(width 0)
				(type default)
			)
			(fill no)
			(layer "F.CrtYd")
		)
		(fp_rect
			(start -0.5842 1.3335)
			(end 0.5842 -1.3335)
			(stroke
				(width 0)
				(type default)
			)
			(fill no)
			(layer "F.Fab")
		)
		(pad "1" smd custom
			(at 0 -0.762 270)
			(size 0.2159 0.2159)
			(layers "F.Cu" "F.Mask" "F.Paste")
			(net "P12V_IN")
			(options
				(clearance outline)
				(anchor circle)
			)
			(primitives
				(gr_poly
					(pts
						(arc
							(start -0.3302 -0.4318)
							(mid -0.402042 -0.402042)
							(end -0.4318 -0.3302)
						)
						(arc
							(start -0.4318 0.3302)
							(mid -0.402042 0.402042)
							(end -0.3302 0.4318)
						)
						(arc
							(start 0.3302 0.4318)
							(mid 0.402042 0.402042)
							(end 0.4318 0.3302)
						)
						(arc
							(start 0.4318 -0.3302)
							(mid 0.402042 -0.402042)
							(end 0.3302 -0.4318)
						)
					)
					(width 0)
					(fill yes)
				)
			)
		)
		(pad "2" smd custom
			(at 0 0.762 270)
			(size 0.2159 0.2159)
			(layers "F.Cu" "F.Mask" "F.Paste")
			(net "GND")
			(options
				(clearance outline)
				(anchor circle)
			)
			(primitives
				(gr_poly
					(pts
						(arc
							(start -0.3302 -0.4318)
							(mid -0.402042 -0.402042)
							(end -0.4318 -0.3302)
						)
						(arc
							(start -0.4318 0.3302)
							(mid -0.402042 0.402042)
							(end -0.3302 0.4318)
						)
						(arc
							(start 0.3302 0.4318)
							(mid 0.402042 0.402042)
							(end 0.4318 0.3302)
						)
						(arc
							(start 0.4318 -0.3302)
							(mid 0.402042 -0.402042)
							(end 0.3302 -0.4318)
						)
					)
					(width 0)
					(fill yes)
				)
			)
		)
	)
	(footprint ""
		(layer "F.Cu")
		(at 29.127196 -378.1044 -90)
		(property "Reference" "Q204"
			(at 0 0 270)
			(layer "F.SilkS")
			(hide yes)
			(effects
				(font
					(size 1.27 1.27)
				)
			)
		)
		(property "Value" "SSM6P39TU-GP"
			(at 0.0508 -11.5824 270)
			(unlocked yes)
			(layer "F.Fab")
			(hide yes)
			(effects
				(font
					(size 1.016 1.016)
					(thickness 0.1524)
				)
			)
		)
		(property "Device Type" "UMT6H30"
			(at 0.0508 -13.1572 270)
			(unlocked yes)
			(layer "F.Fab")
			(hide yes)
			(effects
				(font
					(size 1.016 1.016)
					(thickness 0.1524)
				)
			)
		)
		(duplicate_pad_numbers_are_jumpers no)
		(fp_line
			(start 1.524 0.36449)
			(end -1.27 0.36449)
			(stroke
				(width 0.1524)
				(type default)
			)
			(layer "F.SilkS")
		)
		(fp_line
			(start 1.09347 0)
			(end 1.45796 0.36449)
			(stroke
				(width 0.1524)
				(type default)
			)
			(layer "F.SilkS")
		)
		(fp_line
			(start -1.27 -0.36449)
			(end -1.27 0.36449)
			(stroke
				(width 0.1524)
				(type default)
			)
			(layer "F.SilkS")
		)
		(fp_line
			(start -1.27 -0.36449)
			(end 1.524 -0.36449)
			(stroke
				(width 0.1524)
				(type default)
			)
			(layer "F.SilkS")
		)
		(fp_line
			(start 1.45796 -0.36449)
			(end 1.09347 0)
			(stroke
				(width 0.1524)
				(type default)
			)
			(layer "F.SilkS")
		)
		(fp_line
			(start 1.524 -0.36449)
			(end 1.524 0.36449)
			(stroke
				(width 0.1524)
				(type default)
			)
			(layer "F.SilkS")
		)
		(fp_line
			(start 1.524 -0.36449)
			(end 1.45796 -0.36449)
			(stroke
				(width 0.1524)
				(type default)
			)
			(layer "F.SilkS")
		)
		(fp_line
			(start 1.524 -0.36449)
			(end 1.524 -1.82245)
			(stroke
				(width 0.508)
				(type default)
			)
			(layer "F.SilkS")
		)
		(fp_poly
			(pts
				(xy -0.65024 0.36449) (xy -0.65024 -0.36449) (xy 0.65024 -0.36449) (xy 0.65024 0.36449)
			)
			(stroke
				(width 0)
				(type default)
			)
			(fill yes)
			(layer "F.SilkS")
		)
		(fp_poly
			(pts
				(xy 1.016 -1.0668) (xy 1.016 1.0668) (xy -1.016 1.0668) (xy -1.016 -1.0668)
			)
			(stroke
				(width 0)
				(type default)
			)
			(fill no)
			(layer "F.CrtYd")
		)
		(fp_poly
			(pts
				(xy -1.524 1.905) (xy 1.524 1.905) (xy 1.524 -1.06426) (xy 1.016 -1.06426) (xy 1.016 1.0668) (xy -1.016 1.0668)
				(xy -1.016 -1.0668) (xy 1.524 -1.0668) (xy 1.524 -1.905) (xy -1.524 -1.905)
			)
			(stroke
				(width 0)
				(type default)
			)
			(fill no)
			(layer "F.CrtYd")
		)
		(fp_poly
			(pts
				(xy -1.524 -1.905) (xy -1.524 1.905) (xy 1.524 1.905) (xy 1.524 -1.905)
			)
			(stroke
				(width 0)
				(type default)
			)
			(fill no)
			(layer "F.Fab")
		)
		(pad "1" smd rect
			(at 0.65024 -1.02489 270)
			(size 0.4064 0.8128)
			(layers "F.Cu" "F.Mask" "F.Paste")
			(net "P12V_IN")
		)
		(pad "2" smd rect
			(at 0 -1.02489 270)
			(size 0.4064 0.8128)
			(layers "F.Cu" "F.Mask" "F.Paste")
			(net "FAN_YELLOW_LED0")
		)
		(pad "3" smd rect
			(at -0.65024 -1.02489 270)
			(size 0.4064 0.8128)
			(layers "F.Cu" "F.Mask" "F.Paste")
			(net "FAN_BLUE0")
		)
		(pad "4" smd rect
			(at -0.65024 1.02489 270)
			(size 0.4064 0.8128)
			(layers "F.Cu" "F.Mask" "F.Paste")
			(net "P12V_IN")
		)
		(pad "5" smd rect
			(at 0 1.02489 270)
			(size 0.4064 0.8128)
			(layers "F.Cu" "F.Mask" "F.Paste")
			(net "FAN_BLUE_LED0")
		)
		(pad "6" smd rect
			(at 0.65024 1.02489 270)
			(size 0.4064 0.8128)
			(layers "F.Cu" "F.Mask" "F.Paste")
			(net "FAN_YELLOW_0")
		)
	)
)
